#ISCELL
  mstr_misc dns *
  *
#ISCELL
  pure_quanta quanta_title_block_c *
  *
#ISCELL
  pure_quanta_power design_note *
  *
#ISCELL
  standard offpage *
  page299_i1
#ISCELL
  pure_quanta_power universal_power *
  page299_i10
#ISCELL
  pure_quanta_power universal_gnd *
  page299_i11
#ISCELL
  standard offpage *
  page299_i12
#CELL
  pure_quanta q_cap *
  page299_i129
#CELL
  pure_quanta q_res *
  page299_i130
#CELL
  pure_quanta q_res *
  page299_i131
#CELL
  pure_quanta q_res *
  page299_i132
#CELL
  pure_quanta q_res *
  page299_i133
#CELL
  pure_quanta q_res *
  page299_i134
#ISCELL
  pure_quanta_power universal_power *
  page299_i15
#ISCELL
  pure_quanta_power universal_power *
  page299_i150
#ISCELL
  standard offpage *
  page299_i151
#CELL
  pure_quanta q_cap *
  page299_i152
#ISCELL
  pure_quanta_power universal_gnd *
  page299_i153
#CELL
  pure_quanta q_res *
  page299_i154
#ISCELL
  pure_quanta_power universal_power *
  page299_i155
#ISCELL
  pure_quanta_power universal_gnd *
  page299_i156
#CELL
  pure_quanta mosfet_nch_dual *
  page299_i157
#CELL
  pure_quanta q_res *
  page299_i158
#ISCELL
  pure_quanta_power universal_gnd *
  page299_i159
#ISCELL
  pure_quanta_power universal_gnd *
  page299_i16
#CELL
  pure_quanta mosfet_nch_dual *
  page299_i160
#ISCELL
  pure_quanta_power universal_power *
  page299_i161
#CELL
  pure_quanta q_res *
  page299_i163
#ISCELL
  pure_quanta_power universal_gnd *
  page299_i164
#ISCELL
  standard offpage *
  page299_i165
#CELL
  pure_quanta q_res *
  page299_i166
#CELL
  pure_quanta q_res *
  page299_i167
#CELL
  pure_quanta mosfet_nch_dual *
  page299_i168
#CELL
  pure_quanta mosfet_nch_dual *
  page299_i169
#CELL
  pure_quanta q_res *
  page299_i17
#ISCELL
  standard offpage *
  page299_i170
#CELL
  pure_quanta q_cap *
  page299_i171
#ISCELL
  pure_quanta_power universal_gnd *
  page299_i172
#ISCELL
  pure_quanta_power universal_power *
  page299_i173
#CELL
  pure_quanta q_res *
  page299_i174
#ISCELL
  pure_quanta_power universal_gnd *
  page299_i175
#ISCELL
  pure_quanta_power universal_power *
  page299_i176
#CELL
  pure_quanta q_res *
  page299_i177
#ISCELL
  pure_quanta_power universal_gnd *
  page299_i178
#ISCELL
  pure_quanta_power universal_power *
  page299_i179
#ISCELL
  standard offpage *
  page299_i18
#CELL
  pure_quanta q_res *
  page299_i181
#ISCELL
  pure_quanta_power universal_gnd *
  page299_i182
#ISCELL
  standard offpage *
  page299_i183
#CELL
  pure_quanta q_res *
  page299_i184
#ISCELL
  standard offpage *
  page299_i185
#ISCELL
  pure_quanta_power universal_gnd *
  page299_i186
#CELL
  pure_quanta q_res *
  page299_i187
#ISCELL
  standard offpage *
  page299_i188
#ISCELL
  pure_quanta_power universal_power *
  page299_i190
#ISCELL
  pure_quanta_power universal_gnd *
  page299_i191
#CELL
  pure_quanta q_res *
  page299_i192
#ISCELL
  pure_quanta_power universal_power *
  page299_i193
#ISCELL
  pure_quanta_power universal_gnd *
  page299_i194
#CELL
  pure_quanta q_res *
  page299_i195
#ISCELL
  pure_quanta_power universal_power *
  page299_i196
#ISCELL
  pure_quanta_power universal_gnd *
  page299_i197
#CELL
  pure_quanta q_res *
  page299_i198
#ISCELL
  standard offpage *
  page299_i199
#ISCELL
  pure_quanta_power universal_gnd *
  page299_i2
#ISCELL
  pure_quanta_power universal_power *
  page299_i20
#CELL
  pure_quanta mosfet_nch_dual *
  page299_i200
#CELL
  pure_quanta mosfet_nch_dual *
  page299_i201
#CELL
  pure_quanta q_res *
  page299_i202
#CELL
  pure_quanta mosfet_nch_dual *
  page299_i21
#ISCELL
  pure_quanta_power universal_gnd *
  page299_i22
#CELL
  pure_quanta q_res *
  page299_i23
#ISCELL
  pure_quanta_power universal_power *
  page299_i24
#ISCELL
  pure_quanta_power universal_gnd *
  page299_i25
#CELL
  pure_quanta mosfet_nch_dual *
  page299_i26
#CELL
  pure_quanta q_res *
  page299_i27
#ISCELL
  pure_quanta_power universal_power *
  page299_i28
#ISCELL
  pure_quanta_power universal_gnd *
  page299_i29
#CELL
  pure_quanta q_res *
  page299_i3
#CELL
  pure_quanta q_cap *
  page299_i30
#ISCELL
  standard offpage *
  page299_i31
#CELL
  pure_quanta mosfet_nch_dual *
  page299_i37
#ISCELL
  pure_quanta_power universal_gnd *
  page299_i38
#CELL
  pure_quanta q_res *
  page299_i39
#CELL
  pure_quanta mosfet_nch_dual *
  page299_i40
#ISCELL
  pure_quanta_power universal_power *
  page299_i41
#ISCELL
  pure_quanta_power universal_gnd *
  page299_i42
#CELL
  pure_quanta mosfet_nch_dual *
  page299_i43
#ISCELL
  pure_quanta_power universal_gnd *
  page299_i44
#CELL
  pure_quanta q_res *
  page299_i45
#ISCELL
  pure_quanta_power universal_power *
  page299_i46
#ISCELL
  pure_quanta_power universal_gnd *
  page299_i47
#CELL
  pure_quanta mosfet_nch_dual *
  page299_i48
#CELL
  pure_quanta q_res *
  page299_i49
#ISCELL
  pure_quanta_power universal_power *
  page299_i5
#ISCELL
  pure_quanta_power universal_power *
  page299_i50
#ISCELL
  pure_quanta_power universal_gnd *
  page299_i51
#CELL
  pure_quanta mosfet_nch_dual *
  page299_i52
#CELL
  pure_quanta q_res *
  page299_i53
#ISCELL
  pure_quanta_power universal_power *
  page299_i54
#CELL
  pure_quanta q_res *
  page299_i55
#ISCELL
  pure_quanta_power universal_power *
  page299_i56
#CELL
  pure_quanta mosfet_nch_dual *
  page299_i57
#ISCELL
  pure_quanta_power universal_gnd *
  page299_i58
#CELL
  pure_quanta q_res *
  page299_i59
#ISCELL
  standard offpage *
  page299_i6
#ISCELL
  pure_quanta_power universal_gnd *
  page299_i60
#ISCELL
  pure_quanta_power universal_gnd *
  page299_i61
#ISCELL
  standard offpage *
  page299_i62
#ISCELL
  pure_quanta_power universal_gnd *
  page299_i7
#CELL
  pure_quanta q_cap *
  page299_i71
#ISCELL
  standard offpage *
  page299_i72
#ISCELL
  pure_quanta_power universal_gnd *
  page299_i73
#CELL
  pure_quanta q_cap *
  page299_i74
#ISCELL
  standard offpage *
  page299_i75
#ISCELL
  pure_quanta_power universal_power *
  page299_i83
